# S9S_MB_2U (Grand Teton) — schematic netlist excerpt (pin names and nets, part order shuffled) for the footprints in the layout excerpt that follows; sources: Cadence DE-HDL packaged netlist, KiCad conversion of 03242023_DA0F0TMBIJ0_F0T_Motherboard_J_brd_V01_OCP.brd

C1833  Q_CAP  0.1UF 25V 10% X7R  pkg 0402  page 159 : A = P12V_OCP_V3_2 ; B = GND
R983  Q_RES  33.2 1% CHIP  pkg 0402LF  page 222 : A = FM_PVCCINFAON_CPU0_R_EN ; B = FM_PVCCINFAON_CPU0_EN

(kicad_pcb
	(version 20260206)
	(generator "pcbnew")
	(generator_version "10.0")
	(general
		(thickness 1.6)
		(legacy_teardrops no)
	)
	(paper "A4")
	(title_block
		(title "03242023_DA0F0TMBIJ0_F0T_Motherboard_J_brd_V01_OCP.brd")
		(comment 1 "Grand Teton / footprints 1012-1013 of 6105")
	)
	(layers
		(0 "F.Cu" signal "TOP")
		(4 "In1.Cu" signal "GND")
		(6 "In2.Cu" signal "IN1")
		(8 "In3.Cu" signal "GND1")
		(10 "In4.Cu" signal "IN2")
		(12 "In5.Cu" signal "GND2")
		(14 "In6.Cu" signal "IN3")
		(16 "In7.Cu" signal "GND3")
		(18 "In8.Cu" signal "VCC")
		(20 "In9.Cu" signal "VCC1")
		(22 "In10.Cu" signal "GND4")
		(24 "In11.Cu" signal "IN4")
		(26 "In12.Cu" signal "GND5")
		(28 "In13.Cu" signal "IN5")
		(30 "In14.Cu" signal "GND6")
		(32 "In15.Cu" signal "IN6")
		(34 "In16.Cu" signal "GND7")
		(2 "B.Cu" signal "BOTTOM")
		(9 "F.Adhes" user "F.Adhesive")
		(11 "B.Adhes" user "B.Adhesive")
		(13 "F.Paste" user "Package Geometry/Pastemask Top")
		(15 "B.Paste" user "Package Geometry/Pastemask Bottom")
		(5 "F.SilkS" user "Ref Des/Silkscreen Top")
		(7 "B.SilkS" user "Ref Des/Silkscreen Bottom")
		(1 "F.Mask" user "Board Geometry/Soldermask Top")
		(3 "B.Mask" user "Board Geometry/Soldermask Bottom")
		(17 "Dwgs.User" user "User.Drawings")
		(19 "Cmts.User" user "User.Comments")
		(21 "Eco1.User" user "User.Eco1")
		(23 "Eco2.User" user "User.Eco2")
		(25 "Edge.Cuts" user "Board Geometry/Outline")
		(27 "Margin" user)
		(31 "F.CrtYd" user "Package Geometry/Place Bound Top")
		(29 "B.CrtYd" user "Package Geometry/Place Bound Bottom")
		(35 "F.Fab" user "Ref Des/Assembly Top")
		(33 "B.Fab" user "Ref Des/Assembly Bottom")
	)
	(footprint ""
		(layer "F.Cu")
		(at 66.149982 -15.32763 180)
		(property "Reference" "C1833"
			(at 0 0 180)
			(layer "F.SilkS")
			(hide yes)
			(effects
				(font
					(size 1.27 1.27)
				)
			)
		)
		(property "Value" ""
			(at 0 0 180)
			(layer "F.Fab")
			(effects
				(font
					(size 1.27 1.27)
				)
			)
		)
		(duplicate_pad_numbers_are_jumpers no)
		(fp_line
			(start 0.7874 0.4064)
			(end -0.7874 0.4064)
			(stroke
				(width 0.1524)
				(type default)
			)
			(layer "F.SilkS")
		)
		(fp_line
			(start 0.7874 -0.4064)
			(end 0.7874 0.4064)
			(stroke
				(width 0.1524)
				(type default)
			)
			(layer "F.SilkS")
		)
		(fp_line
			(start -0.7874 0.4064)
			(end -0.7874 -0.4064)
			(stroke
				(width 0.1524)
				(type default)
			)
			(layer "F.SilkS")
		)
		(fp_line
			(start -0.7874 -0.4064)
			(end 0.7874 -0.4064)
			(stroke
				(width 0.1524)
				(type default)
			)
			(layer "F.SilkS")
		)
		(fp_line
			(start 0.67945 0.3048)
			(end 0.120396 0.3048)
			(stroke
				(width 0.1)
				(type default)
			)
			(layer "F.Fab")
		)
		(fp_line
			(start 0.67945 -0.3048)
			(end 0.67945 0.3048)
			(stroke
				(width 0.1)
				(type default)
			)
			(layer "F.Fab")
		)
		(fp_line
			(start 0.12065 -0.2794)
			(end 0.12065 -0.3048)
			(stroke
				(width 0.1)
				(type default)
			)
			(layer "F.Fab")
		)
		(fp_line
			(start 0.12065 -0.3048)
			(end 0.67945 -0.3048)
			(stroke
				(width 0.1)
				(type default)
			)
			(layer "F.Fab")
		)
		(fp_line
			(start 0.120396 0.3048)
			(end 0.120396 0.2794)
			(stroke
				(width 0.1)
				(type default)
			)
			(layer "F.Fab")
		)
		(fp_line
			(start 0.120396 0.2794)
			(end -0.12065 0.2794)
			(stroke
				(width 0.1)
				(type default)
			)
			(layer "F.Fab")
		)
		(fp_line
			(start -0.12065 0.3048)
			(end -0.67945 0.3048)
			(stroke
				(width 0.1)
				(type default)
			)
			(layer "F.Fab")
		)
		(fp_line
			(start -0.12065 0.2794)
			(end -0.12065 0.3048)
			(stroke
				(width 0.1)
				(type default)
			)
			(layer "F.Fab")
		)
		(fp_line
			(start -0.12065 -0.2794)
			(end 0.12065 -0.2794)
			(stroke
				(width 0.1)
				(type default)
			)
			(layer "F.Fab")
		)
		(fp_line
			(start -0.12065 -0.305054)
			(end -0.12065 -0.2794)
			(stroke
				(width 0.1)
				(type default)
			)
			(layer "F.Fab")
		)
		(fp_line
			(start -0.67945 0.3048)
			(end -0.67945 -0.305054)
			(stroke
				(width 0.1)
				(type default)
			)
			(layer "F.Fab")
		)
		(fp_line
			(start -0.67945 -0.305054)
			(end -0.12065 -0.305054)
			(stroke
				(width 0.1)
				(type default)
			)
			(layer "F.Fab")
		)
		(pad "1" smd circle
			(at -0.40005 0 180)
			(size 0 0)
			(layers "F.Cu" "F.Mask" "F.Paste")
			(net "P12V_OCP_V3_2")
		)
		(pad "2" smd circle
			(at 0.40005 0 180)
			(size 0 0)
			(layers "F.Cu" "F.Mask" "F.Paste")
			(net "GND")
		)
	)
	(footprint ""
		(layer "F.Cu")
		(at 157.02788 -120.106948 180)
		(property "Reference" "R983"
			(at 0 0 180)
			(layer "F.SilkS")
			(hide yes)
			(effects
				(font
					(size 1.27 1.27)
				)
			)
		)
		(property "Value" ""
			(at 0 0 180)
			(layer "F.Fab")
			(effects
				(font
					(size 1.27 1.27)
				)
			)
		)
		(duplicate_pad_numbers_are_jumpers no)
		(fp_line
			(start 0.7874 0.4064)
			(end -0.7874 0.4064)
			(stroke
				(width 0.1524)
				(type default)
			)
			(layer "F.SilkS")
		)
		(fp_line
			(start 0.7874 -0.4064)
			(end 0.7874 0.4064)
			(stroke
				(width 0.1524)
				(type default)
			)
			(layer "F.SilkS")
		)
		(fp_line
			(start -0.7874 0.4064)
			(end -0.7874 -0.4064)
			(stroke
				(width 0.1524)
				(type default)
			)
			(layer "F.SilkS")
		)
		(fp_line
			(start -0.7874 -0.4064)
			(end 0.7874 -0.4064)
			(stroke
				(width 0.1524)
				(type default)
			)
			(layer "F.SilkS")
		)
		(fp_line
			(start 0.67945 0.3048)
			(end 0.120396 0.3048)
			(stroke
				(width 0.1)
				(type default)
			)
			(layer "F.Fab")
		)
		(fp_line
			(start 0.67945 -0.3048)
			(end 0.67945 0.3048)
			(stroke
				(width 0.1)
				(type default)
			)
			(layer "F.Fab")
		)
		(fp_line
			(start 0.12065 -0.2794)
			(end 0.12065 -0.3048)
			(stroke
				(width 0.1)
				(type default)
			)
			(layer "F.Fab")
		)
		(fp_line
			(start 0.12065 -0.3048)
			(end 0.67945 -0.3048)
			(stroke
				(width 0.1)
				(type default)
			)
			(layer "F.Fab")
		)
		(fp_line
			(start 0.120396 0.3048)
			(end 0.120396 0.2794)
			(stroke
				(width 0.1)
				(type default)
			)
			(layer "F.Fab")
		)
		(fp_line
			(start 0.120396 0.2794)
			(end -0.12065 0.2794)
			(stroke
				(width 0.1)
				(type default)
			)
			(layer "F.Fab")
		)
		(fp_line
			(start -0.12065 0.3048)
			(end -0.67945 0.3048)
			(stroke
				(width 0.1)
				(type default)
			)
			(layer "F.Fab")
		)
		(fp_line
			(start -0.12065 0.2794)
			(end -0.12065 0.3048)
			(stroke
				(width 0.1)
				(type default)
			)
			(layer "F.Fab")
		)
		(fp_line
			(start -0.12065 -0.2794)
			(end 0.12065 -0.2794)
			(stroke
				(width 0.1)
				(type default)
			)
			(layer "F.Fab")
		)
		(fp_line
			(start -0.12065 -0.305054)
			(end -0.12065 -0.2794)
			(stroke
				(width 0.1)
				(type default)
			)
			(layer "F.Fab")
		)
		(fp_line
			(start -0.67945 0.3048)
			(end -0.67945 -0.305054)
			(stroke
				(width 0.1)
				(type default)
			)
			(layer "F.Fab")
		)
		(fp_line
			(start -0.67945 -0.305054)
			(end -0.12065 -0.305054)
			(stroke
				(width 0.1)
				(type default)
			)
			(layer "F.Fab")
		)
		(pad "1" smd circle
			(at -0.40005 0 180)
			(size 0 0)
			(layers "F.Cu" "F.Mask" "F.Paste")
			(net "FM_PVCCINFAON_CPU0_R_EN")
		)
		(pad "2" smd circle
			(at 0.40005 0 180)
			(size 0 0)
			(layers "F.Cu" "F.Mask" "F.Paste")
			(net "FM_PVCCINFAON_CPU0_EN")
		)
	)
)
